# BASEBOARD_FAB2 (Tioga Pass) — schematic netlist excerpt (pin names and nets, part order shuffled) for the footprints in the layout excerpt that follows; sources: Cadence DE-HDL packaged netlist, KiCad conversion of Wiwynn_Tioga_Pass_MB.brd

R7B19  RES  0 5.0% CHIP  pkg 0603  page 232 : A = VR_PVPP_DEF_BOOT ; B = VR_PVPP_DEF_BOOT_R
R8B13  RES  1.8K 1% CHIP  pkg 0402  page 91 : A = PVPP_ABC ; B = SMB_HFI1_CPU0_LVC2_SDA
C1F13  CAP  0.22UF 16V 10% X7R  pkg 0402  page 181 : A = P3E_CPU1_PE3_MP_C_TXN<3> ; B = P3E_CPU1_PE3_MP_TXN<3>

(kicad_pcb
	(version 20260206)
	(generator "pcbnew")
	(generator_version "10.0")
	(general
		(thickness 1.6)
		(legacy_teardrops no)
	)
	(paper "A4")
	(title_block
		(title "Wiwynn_Tioga_Pass_MB.brd")
		(comment 1 "Tioga Pass / footprints 790-792 of 4770")
	)
	(layers
		(0 "F.Cu" signal "TOP")
		(4 "In1.Cu" signal "L2GND")
		(6 "In2.Cu" signal "L3")
		(8 "In3.Cu" signal "L4GND")
		(10 "In4.Cu" signal "L5")
		(12 "In5.Cu" signal "L6GND")
		(14 "In6.Cu" signal "L7VCC")
		(16 "In7.Cu" signal "L8VCC")
		(18 "In8.Cu" signal "L9GND")
		(20 "In9.Cu" signal "L10")
		(22 "In10.Cu" signal "L11GND")
		(24 "In11.Cu" signal "L12")
		(26 "In12.Cu" signal "L13GND")
		(2 "B.Cu" signal "BOTTOM")
		(9 "F.Adhes" user "F.Adhesive")
		(11 "B.Adhes" user "B.Adhesive")
		(13 "F.Paste" user "Package Geometry/Pastemask Top")
		(15 "B.Paste" user "Package Geometry/Pastemask Bottom")
		(5 "F.SilkS" user "Ref Des/Silkscreen Top")
		(7 "B.SilkS" user "Ref Des/Silkscreen Bottom")
		(1 "F.Mask" user "Board Geometry/Soldermask Top")
		(3 "B.Mask" user "Board Geometry/Soldermask Bottom")
		(17 "Dwgs.User" user "User.Drawings")
		(19 "Cmts.User" user "User.Comments")
		(21 "Eco1.User" user "User.Eco1")
		(23 "Eco2.User" user "User.Eco2")
		(25 "Edge.Cuts" user "Board Geometry/Outline")
		(27 "Margin" user)
		(31 "F.CrtYd" user "Package Geometry/Place Bound Top")
		(29 "B.CrtYd" user "Package Geometry/Place Bound Bottom")
		(35 "F.Fab" user "Ref Des/Assembly Top")
		(33 "B.Fab" user "Ref Des/Assembly Bottom")
	)
	(footprint ""
		(layer "F.Cu")
		(at 339.258656 -131.977384)
		(property "Reference" "R7B19"
			(at 1.01473 0.656336 270)
			(unlocked yes)
			(layer "F.SilkS")
			(effects
				(font
					(size 0.4064 0.254)
					(thickness 0.1524)
				)
			)
		)
		(property "Value" ""
			(at 0 0 0)
			(layer "F.Fab")
			(effects
				(font
					(size 1.27 1.27)
				)
			)
		)
		(duplicate_pad_numbers_are_jumpers no)
		(fp_poly
			(pts
				(xy -0.4953 -0.2032) (xy 0.4953 -0.2032) (xy 0.4953 1.6002) (xy -0.4953 1.6002)
			)
			(stroke
				(width 0)
				(type default)
			)
			(fill no)
			(layer "F.CrtYd")
		)
		(fp_line
			(start -0.4953 -0.2032)
			(end 0.4953 -0.2032)
			(stroke
				(width 0.1)
				(type default)
			)
			(layer "F.Fab")
		)
		(fp_line
			(start -0.4953 1.6002)
			(end -0.4953 -0.2032)
			(stroke
				(width 0.1)
				(type default)
			)
			(layer "F.Fab")
		)
		(fp_line
			(start 0.4953 -0.2032)
			(end 0.4953 1.6002)
			(stroke
				(width 0.1)
				(type default)
			)
			(layer "F.Fab")
		)
		(fp_line
			(start 0.4953 1.6002)
			(end -0.4953 1.6002)
			(stroke
				(width 0.1)
				(type default)
			)
			(layer "F.Fab")
		)
		(pad "1" smd rect
			(at 0 0)
			(size 0.762 0.889)
			(layers "F.Cu" "F.Mask" "F.Paste")
			(net "VR_PVPP_DEF_BOOT")
		)
		(pad "2" smd rect
			(at 0 1.397)
			(size 0.762 0.889)
			(layers "F.Cu" "F.Mask" "F.Paste")
			(net "VR_PVPP_DEF_BOOT_R")
		)
		(zone
			(layer "F.Cu")
			(hatch none 0.5)
			(connect_pads
				(clearance 0)
			)
			(min_thickness 0.25)
			(keepout
				(tracks not_allowed)
				(vias allowed)
				(pads allowed)
				(copperpour not_allowed)
				(footprints allowed)
			)
			(placement
				(enabled no)
				(sheetname "")
			)
			(fill
				(thermal_gap 0.5)
				(thermal_bridge_width 0.5)
				(island_removal_mode 0)
			)
			(polygon
				(pts
					(xy 338.877656 -131.024884) (xy 339.639656 -131.024884) (xy 339.639656 -131.532884) (xy 338.877656 -131.532884)
				)
			)
		)
		(zone
			(layer "F.Cu")
			(hatch none 0.5)
			(connect_pads
				(clearance 0)
			)
			(min_thickness 0.25)
			(keepout
				(tracks allowed)
				(vias not_allowed)
				(pads allowed)
				(copperpour not_allowed)
				(footprints allowed)
			)
			(placement
				(enabled no)
				(sheetname "")
			)
			(fill
				(thermal_gap 0.5)
				(thermal_bridge_width 0.5)
				(island_removal_mode 0)
			)
			(polygon
				(pts
					(xy 339.639656 -131.024884) (xy 339.639656 -131.532884) (xy 338.877656 -131.532884) (xy 338.877656 -131.024884)
				)
			)
		)
	)
	(footprint ""
		(layer "F.Cu")
		(at 13.8938 -28.575 90)
		(property "Reference" "C1F13"
			(at 0 0 90)
			(layer "F.SilkS")
			(hide yes)
			(effects
				(font
					(size 1.27 1.27)
				)
			)
		)
		(property "Value" ""
			(at 0 0 90)
			(layer "F.Fab")
			(effects
				(font
					(size 1.27 1.27)
				)
			)
		)
		(duplicate_pad_numbers_are_jumpers no)
		(fp_rect
			(start -0.3048 -0.1016)
			(end 0.3048 0.9906)
			(stroke
				(width 0)
				(type default)
			)
			(fill no)
			(layer "F.CrtYd")
		)
		(fp_line
			(start 0.3048 -0.1016)
			(end -0.3048 -0.1016)
			(stroke
				(width 0.1)
				(type default)
			)
			(layer "F.Fab")
		)
		(fp_line
			(start -0.3048 -0.1016)
			(end -0.3048 0.9906)
			(stroke
				(width 0.1)
				(type default)
			)
			(layer "F.Fab")
		)
		(fp_line
			(start 0.3048 0.9906)
			(end 0.3048 -0.1016)
			(stroke
				(width 0.1)
				(type default)
			)
			(layer "F.Fab")
		)
		(fp_line
			(start -0.3048 0.9906)
			(end 0.3048 0.9906)
			(stroke
				(width 0.1)
				(type default)
			)
			(layer "F.Fab")
		)
		(pad "1" smd rect
			(at 0 0 90)
			(size 0.508 0.508)
			(layers "F.Cu" "F.Mask" "F.Paste")
			(net "P3E_CPU1_PE3_MP_C_TXN<3>")
		)
		(pad "2" smd rect
			(at 0 0.889 90)
			(size 0.508 0.508)
			(layers "F.Cu" "F.Mask" "F.Paste")
			(net "P3E_CPU1_PE3_MP_TXN<3>")
		)
		(zone
			(layer "F.Cu")
			(hatch none 0.5)
			(connect_pads
				(clearance 0)
			)
			(min_thickness 0.25)
			(keepout
				(tracks allowed)
				(vias not_allowed)
				(pads allowed)
				(copperpour not_allowed)
				(footprints allowed)
			)
			(placement
				(enabled no)
				(sheetname "")
			)
			(fill
				(thermal_gap 0.5)
				(thermal_bridge_width 0.5)
				(island_removal_mode 0)
			)
			(polygon
				(pts
					(xy 14.1478 -28.321) (xy 14.5288 -28.321) (xy 14.5288 -28.829) (xy 14.1478 -28.829)
				)
			)
		)
		(zone
			(layer "F.Cu")
			(hatch none 0.5)
			(connect_pads
				(clearance 0)
			)
			(min_thickness 0.25)
			(keepout
				(tracks not_allowed)
				(vias allowed)
				(pads allowed)
				(copperpour not_allowed)
				(footprints allowed)
			)
			(placement
				(enabled no)
				(sheetname "")
			)
			(fill
				(thermal_gap 0.5)
				(thermal_bridge_width 0.5)
				(island_removal_mode 0)
			)
			(polygon
				(pts
					(xy 14.1478 -28.321) (xy 14.5288 -28.321) (xy 14.5288 -28.829) (xy 14.1478 -28.829)
				)
			)
		)
	)
	(footprint ""
		(layer "F.Cu")
		(at 426.5041 -125.6792 -90)
		(property "Reference" "R8B13"
			(at 0 0 270)
			(layer "F.SilkS")
			(hide yes)
			(effects
				(font
					(size 1.27 1.27)
				)
			)
		)
		(property "Value" ""
			(at 0 0 270)
			(layer "F.Fab")
			(effects
				(font
					(size 1.27 1.27)
				)
			)
		)
		(duplicate_pad_numbers_are_jumpers no)
		(fp_poly
			(pts
				(xy -0.2794 -0.1016) (xy 0.2794 -0.1016) (xy 0.2794 0.9906) (xy -0.2794 0.9906)
			)
			(stroke
				(width 0)
				(type default)
			)
			(fill no)
			(layer "F.CrtYd")
		)
		(fp_line
			(start -0.2794 0.9906)
			(end 0.2794 0.9906)
			(stroke
				(width 0.1)
				(type default)
			)
			(layer "F.Fab")
		)
		(fp_line
			(start 0.2794 0.9906)
			(end 0.2794 -0.1016)
			(stroke
				(width 0.1)
				(type default)
			)
			(layer "F.Fab")
		)
		(fp_line
			(start -0.2794 -0.1016)
			(end -0.2794 0.9906)
			(stroke
				(width 0.1)
				(type default)
			)
			(layer "F.Fab")
		)
		(fp_line
			(start 0.2794 -0.1016)
			(end -0.2794 -0.1016)
			(stroke
				(width 0.1)
				(type default)
			)
			(layer "F.Fab")
		)
		(pad "1" smd rect
			(at 0 0 270)
			(size 0.508 0.508)
			(layers "F.Cu" "F.Mask" "F.Paste")
			(net "PVPP_ABC")
		)
		(pad "2" smd rect
			(at 0 0.889 270)
			(size 0.508 0.508)
			(layers "F.Cu" "F.Mask" "F.Paste")
			(net "SMB_HFI1_CPU0_LVC2_SDA")
		)
		(zone
			(layer "F.Cu")
			(hatch none 0.5)
			(connect_pads
				(clearance 0)
			)
			(min_thickness 0.25)
			(keepout
				(tracks not_allowed)
				(vias allowed)
				(pads allowed)
				(copperpour not_allowed)
				(footprints allowed)
			)
			(placement
				(enabled no)
				(sheetname "")
			)
			(fill
				(thermal_gap 0.5)
				(thermal_bridge_width 0.5)
				(island_removal_mode 0)
			)
			(polygon
				(pts
					(xy 425.8691 -125.9332) (xy 425.8691 -125.4252) (xy 426.2501 -125.4252) (xy 426.2501 -125.9332)
				)
			)
		)
		(zone
			(layer "F.Cu")
			(hatch none 0.5)
			(connect_pads
				(clearance 0)
			)
			(min_thickness 0.25)
			(keepout
				(tracks allowed)
				(vias not_allowed)
				(pads allowed)
				(copperpour not_allowed)
				(footprints allowed)
			)
			(placement
				(enabled no)
				(sheetname "")
			)
			(fill
				(thermal_gap 0.5)
				(thermal_bridge_width 0.5)
				(island_removal_mode 0)
			)
			(polygon
				(pts
					(xy 426.2501 -125.9332) (xy 426.2501 -125.4252) (xy 425.8691 -125.4252) (xy 425.8691 -125.9332)
				)
			)
		)
	)
)
